# ZAIUS-LBB-EVT2-X01-BOM-X03-20161116.xls — Summary (bom)
| PLATFORM SOURCING AND PSL COMPLIANCE |  |  |  |  |  |  |  |  |  |
| Platform Name: |  |  |  |  |  |  |  |  |  |
| REVISION HISTORY |  |  |  |  |  |  |  |  |  |
| BOM Revision: | ECR # | Revision Description | Originator | Date |  |  |  |  |  |
| Commodity Sourcing | # of components (X00 BOM) | % of Total | # of components (X01 BOM) | % of Total | # of components (X02 BOM) | % of Total | # of components (RTS) | % of Total | Risk Mitigation Plans in Place |
| Sole Source |  |  |  |  |  |  |  |  |  |
| Single Source |  |  |  |  |  |  |  |  |  |
| Multiple |  |  |  |  |  |  |  |  | NA |
| Total |  |  |  |  |  |  |  |  | NA |
|  |  | # of components | # of components aligned with Dell PSL* | % PSL alignment |  |  |  |  |  |
| Class 1 (Dell Managed) |  |  |  |  |  |  |  |  |  |
| Class 2 (ODM Managed to Dell PSL) |  |  |  |  |  |  |  |  |  |
| All other components(ODM Managed to ODM PSL) |  |  |  |  |  |  |  |  |  |
| *RFQ and/or Contract will list requirements for complying with Dell's PSL |  |  |  |  |  |  |  |  |  |
| Reference for quotation |  |  |  |  |  |  |  |  |  |
